# S9S_MB_2U (Grand Teton) — schematic netlist excerpt (pin names and nets, part order shuffled) for the footprints in the layout excerpt that follows; sources: Cadence DE-HDL packaged netlist, KiCad conversion of 03242023_DA0F0TMBIJ0_F0T_Motherboard_J_brd_V01_OCP.brd

R755  Q_RES  10 1% CHIP  pkg 0402LF  page 132 : A = JTAG_DBP_PREQ_N ; B = H_DBP_PREQ_N_PCH
C2327  Q_CAP  12PF 50V 5% EMPTY  pkg C0402  page 196 : A = USB_HUB_2_XTAL_OUT ; B = GND

(kicad_pcb
	(version 20260206)
	(generator "pcbnew")
	(generator_version "10.0")
	(general
		(thickness 1.6)
		(legacy_teardrops no)
	)
	(paper "A4")
	(title_block
		(title "03242023_DA0F0TMBIJ0_F0T_Motherboard_J_brd_V01_OCP.brd")
		(comment 1 "Grand Teton / footprints 3688-3689 of 6105")
	)
	(layers
		(0 "F.Cu" signal "TOP")
		(4 "In1.Cu" signal "GND")
		(6 "In2.Cu" signal "IN1")
		(8 "In3.Cu" signal "GND1")
		(10 "In4.Cu" signal "IN2")
		(12 "In5.Cu" signal "GND2")
		(14 "In6.Cu" signal "IN3")
		(16 "In7.Cu" signal "GND3")
		(18 "In8.Cu" signal "VCC")
		(20 "In9.Cu" signal "VCC1")
		(22 "In10.Cu" signal "GND4")
		(24 "In11.Cu" signal "IN4")
		(26 "In12.Cu" signal "GND5")
		(28 "In13.Cu" signal "IN5")
		(30 "In14.Cu" signal "GND6")
		(32 "In15.Cu" signal "IN6")
		(34 "In16.Cu" signal "GND7")
		(2 "B.Cu" signal "BOTTOM")
		(9 "F.Adhes" user "F.Adhesive")
		(11 "B.Adhes" user "B.Adhesive")
		(13 "F.Paste" user "Package Geometry/Pastemask Top")
		(15 "B.Paste" user "Package Geometry/Pastemask Bottom")
		(5 "F.SilkS" user "Ref Des/Silkscreen Top")
		(7 "B.SilkS" user "Ref Des/Silkscreen Bottom")
		(1 "F.Mask" user "Board Geometry/Soldermask Top")
		(3 "B.Mask" user "Board Geometry/Soldermask Bottom")
		(17 "Dwgs.User" user "User.Drawings")
		(19 "Cmts.User" user "User.Comments")
		(21 "Eco1.User" user "User.Eco1")
		(23 "Eco2.User" user "User.Eco2")
		(25 "Edge.Cuts" user "Board Geometry/Outline")
		(27 "Margin" user)
		(31 "F.CrtYd" user "Package Geometry/Place Bound Top")
		(29 "B.CrtYd" user "Package Geometry/Place Bound Bottom")
		(35 "F.Fab" user "Ref Des/Assembly Top")
		(33 "B.Fab" user "Ref Des/Assembly Bottom")
	)
	(footprint ""
		(layer "F.Cu")
		(at 374.16359 -66.898012)
		(property "Reference" "R755"
			(at 0 0 0)
			(layer "F.SilkS")
			(hide yes)
			(effects
				(font
					(size 1.27 1.27)
				)
			)
		)
		(property "Value" ""
			(at 0 0 0)
			(layer "F.Fab")
			(effects
				(font
					(size 1.27 1.27)
				)
			)
		)
		(duplicate_pad_numbers_are_jumpers no)
		(fp_line
			(start -0.7874 -0.4064)
			(end 0.7874 -0.4064)
			(stroke
				(width 0.1524)
				(type default)
			)
			(layer "F.SilkS")
		)
		(fp_line
			(start -0.7874 0.4064)
			(end -0.7874 -0.4064)
			(stroke
				(width 0.1524)
				(type default)
			)
			(layer "F.SilkS")
		)
		(fp_line
			(start 0.7874 -0.4064)
			(end 0.7874 0.4064)
			(stroke
				(width 0.1524)
				(type default)
			)
			(layer "F.SilkS")
		)
		(fp_line
			(start 0.7874 0.4064)
			(end -0.7874 0.4064)
			(stroke
				(width 0.1524)
				(type default)
			)
			(layer "F.SilkS")
		)
		(fp_line
			(start -0.67945 -0.305054)
			(end -0.12065 -0.305054)
			(stroke
				(width 0.1)
				(type default)
			)
			(layer "F.Fab")
		)
		(fp_line
			(start -0.67945 0.3048)
			(end -0.67945 -0.305054)
			(stroke
				(width 0.1)
				(type default)
			)
			(layer "F.Fab")
		)
		(fp_line
			(start -0.12065 -0.305054)
			(end -0.12065 -0.2794)
			(stroke
				(width 0.1)
				(type default)
			)
			(layer "F.Fab")
		)
		(fp_line
			(start -0.12065 -0.2794)
			(end 0.12065 -0.2794)
			(stroke
				(width 0.1)
				(type default)
			)
			(layer "F.Fab")
		)
		(fp_line
			(start -0.12065 0.2794)
			(end -0.12065 0.3048)
			(stroke
				(width 0.1)
				(type default)
			)
			(layer "F.Fab")
		)
		(fp_line
			(start -0.12065 0.3048)
			(end -0.67945 0.3048)
			(stroke
				(width 0.1)
				(type default)
			)
			(layer "F.Fab")
		)
		(fp_line
			(start 0.120396 0.2794)
			(end -0.12065 0.2794)
			(stroke
				(width 0.1)
				(type default)
			)
			(layer "F.Fab")
		)
		(fp_line
			(start 0.120396 0.3048)
			(end 0.120396 0.2794)
			(stroke
				(width 0.1)
				(type default)
			)
			(layer "F.Fab")
		)
		(fp_line
			(start 0.12065 -0.3048)
			(end 0.67945 -0.3048)
			(stroke
				(width 0.1)
				(type default)
			)
			(layer "F.Fab")
		)
		(fp_line
			(start 0.12065 -0.2794)
			(end 0.12065 -0.3048)
			(stroke
				(width 0.1)
				(type default)
			)
			(layer "F.Fab")
		)
		(fp_line
			(start 0.67945 -0.3048)
			(end 0.67945 0.3048)
			(stroke
				(width 0.1)
				(type default)
			)
			(layer "F.Fab")
		)
		(fp_line
			(start 0.67945 0.3048)
			(end 0.120396 0.3048)
			(stroke
				(width 0.1)
				(type default)
			)
			(layer "F.Fab")
		)
		(pad "1" smd circle
			(at -0.40005 0)
			(size 0 0)
			(layers "F.Cu" "F.Mask" "F.Paste")
			(net "JTAG_DBP_PREQ_N")
		)
		(pad "2" smd circle
			(at 0.40005 0)
			(size 0 0)
			(layers "F.Cu" "F.Mask" "F.Paste")
			(net "H_DBP_PREQ_N_PCH")
		)
	)
	(footprint ""
		(layer "F.Cu")
		(at 152.09393 -36.741608 -90)
		(property "Reference" "C2327"
			(at 0 0 270)
			(layer "F.SilkS")
			(hide yes)
			(effects
				(font
					(size 1.27 1.27)
				)
			)
		)
		(property "Value" ""
			(at 0 0 270)
			(layer "F.Fab")
			(effects
				(font
					(size 1.27 1.27)
				)
			)
		)
		(duplicate_pad_numbers_are_jumpers no)
		(fp_line
			(start -0.7874 0.4064)
			(end -0.7874 -0.4064)
			(stroke
				(width 0.1524)
				(type default)
			)
			(layer "F.SilkS")
		)
		(fp_line
			(start 0.7874 0.4064)
			(end -0.7874 0.4064)
			(stroke
				(width 0.1524)
				(type default)
			)
			(layer "F.SilkS")
		)
		(fp_line
			(start -0.7874 -0.4064)
			(end 0.7874 -0.4064)
			(stroke
				(width 0.1524)
				(type default)
			)
			(layer "F.SilkS")
		)
		(fp_line
			(start 0.7874 -0.4064)
			(end 0.7874 0.4064)
			(stroke
				(width 0.1524)
				(type default)
			)
			(layer "F.SilkS")
		)
		(fp_line
			(start -0.67945 0.3048)
			(end -0.67945 -0.305054)
			(stroke
				(width 0.1)
				(type default)
			)
			(layer "F.Fab")
		)
		(fp_line
			(start -0.12065 0.3048)
			(end -0.67945 0.3048)
			(stroke
				(width 0.1)
				(type default)
			)
			(layer "F.Fab")
		)
		(fp_line
			(start 0.120396 0.3048)
			(end 0.120396 0.2794)
			(stroke
				(width 0.1)
				(type default)
			)
			(layer "F.Fab")
		)
		(fp_line
			(start 0.67945 0.3048)
			(end 0.120396 0.3048)
			(stroke
				(width 0.1)
				(type default)
			)
			(layer "F.Fab")
		)
		(fp_line
			(start -0.12065 0.2794)
			(end -0.12065 0.3048)
			(stroke
				(width 0.1)
				(type default)
			)
			(layer "F.Fab")
		)
		(fp_line
			(start 0.120396 0.2794)
			(end -0.12065 0.2794)
			(stroke
				(width 0.1)
				(type default)
			)
			(layer "F.Fab")
		)
		(fp_line
			(start -0.12065 -0.2794)
			(end 0.12065 -0.2794)
			(stroke
				(width 0.1)
				(type default)
			)
			(layer "F.Fab")
		)
		(fp_line
			(start 0.12065 -0.2794)
			(end 0.12065 -0.3048)
			(stroke
				(width 0.1)
				(type default)
			)
			(layer "F.Fab")
		)
		(fp_line
			(start 0.12065 -0.3048)
			(end 0.67945 -0.3048)
			(stroke
				(width 0.1)
				(type default)
			)
			(layer "F.Fab")
		)
		(fp_line
			(start 0.67945 -0.3048)
			(end 0.67945 0.3048)
			(stroke
				(width 0.1)
				(type default)
			)
			(layer "F.Fab")
		)
		(fp_line
			(start -0.67945 -0.305054)
			(end -0.12065 -0.305054)
			(stroke
				(width 0.1)
				(type default)
			)
			(layer "F.Fab")
		)
		(fp_line
			(start -0.12065 -0.305054)
			(end -0.12065 -0.2794)
			(stroke
				(width 0.1)
				(type default)
			)
			(layer "F.Fab")
		)
		(pad "1" smd circle
			(at -0.40005 0 270)
			(size 0 0)
			(layers "F.Cu" "F.Mask" "F.Paste")
			(net "USB_HUB_2_XTAL_OUT")
		)
		(pad "2" smd circle
			(at 0.40005 0 270)
			(size 0 0)
			(layers "F.Cu" "F.Mask" "F.Paste")
			(net "GND")
		)
	)
)
